(kicad_pcb
	(version 20260206)
	(generator "pcbnew")
	(generator_version "10.0")
	(general
		(thickness 1.6)
		(legacy_teardrops no)
	)
	(paper "A4")
	(title_block
		(title "04192023_DAF0TMB3IC0_F0TG_MB_C_brd_V02_OCP.brd")
		(comment 1 "Grand Teton / footprints 7512-7518 of 8354")
	)
	(layers
		(0 "F.Cu" signal "TOP")
		(4 "In1.Cu" signal "GND")
		(6 "In2.Cu" signal "IN1")
		(8 "In3.Cu" signal "GND1")
		(10 "In4.Cu" signal "IN2")
		(12 "In5.Cu" signal "GND2")
		(14 "In6.Cu" signal "IN3")
		(16 "In7.Cu" signal "GND3")
		(18 "In8.Cu" signal "VCC")
		(20 "In9.Cu" signal "VCC1")
		(22 "In10.Cu" signal "GND4")
		(24 "In11.Cu" signal "IN4")
		(26 "In12.Cu" signal "GND5")
		(28 "In13.Cu" signal "IN5")
		(30 "In14.Cu" signal "GND6")
		(32 "In15.Cu" signal "IN6")
		(34 "In16.Cu" signal "GND7")
		(2 "B.Cu" signal "BOTTOM")
		(9 "F.Adhes" user "F.Adhesive")
		(11 "B.Adhes" user "B.Adhesive")
		(13 "F.Paste" user "Package Geometry/Pastemask Top")
		(15 "B.Paste" user "Package Geometry/Pastemask Bottom")
		(5 "F.SilkS" user "Ref Des/Silkscreen Top")
		(7 "B.SilkS" user "Ref Des/Silkscreen Bottom")
		(1 "F.Mask" user "Board Geometry/Soldermask Top")
		(3 "B.Mask" user "Board Geometry/Soldermask Bottom")
		(17 "Dwgs.User" user "User.Drawings")
		(19 "Cmts.User" user "User.Comments")
		(21 "Eco1.User" user "User.Eco1")
		(23 "Eco2.User" user "User.Eco2")
		(25 "Edge.Cuts" user "Board Geometry/Outline")
		(27 "Margin" user)
		(31 "F.CrtYd" user "Package Geometry/Place Bound Top")
		(29 "B.CrtYd" user "Package Geometry/Place Bound Bottom")
		(35 "F.Fab" user "Ref Des/Assembly Top")
		(33 "B.Fab" user "Ref Des/Assembly Bottom")
	)
	(footprint ""
		(layer "B.Cu")
		(at 353.231958 -245.487952)
		(property "Reference" "C245"
			(at 0 0 0)
			(layer "B.SilkS")
			(hide yes)
			(effects
				(font
					(size 1.27 1.27)
				)
				(justify mirror)
			)
		)
		(property "Value" ""
			(at 0 0 0)
			(layer "B.Fab")
			(effects
				(font
					(size 1.27 1.27)
				)
				(justify mirror)
			)
		)
		(duplicate_pad_numbers_are_jumpers no)
		(fp_line
			(start -0.7874 -0.4064)
			(end -0.7874 0.4064)
			(stroke
				(width 0.1524)
				(type default)
			)
			(layer "B.SilkS")
		)
		(fp_line
			(start -0.7874 0.4064)
			(end 0.7874 0.4064)
			(stroke
				(width 0.1524)
				(type default)
			)
			(layer "B.SilkS")
		)
		(fp_line
			(start 0.7874 -0.4064)
			(end -0.7874 -0.4064)
			(stroke
				(width 0.1524)
				(type default)
			)
			(layer "B.SilkS")
		)
		(fp_line
			(start 0.7874 0.4064)
			(end 0.7874 -0.4064)
			(stroke
				(width 0.1524)
				(type default)
			)
			(layer "B.SilkS")
		)
		(fp_line
			(start -0.67945 -0.3048)
			(end -0.67945 0.3048)
			(stroke
				(width 0.1)
				(type default)
			)
			(layer "B.Fab")
		)
		(fp_line
			(start -0.67945 0.3048)
			(end -0.120396 0.3048)
			(stroke
				(width 0.1)
				(type default)
			)
			(layer "B.Fab")
		)
		(fp_line
			(start -0.12065 -0.3048)
			(end -0.67945 -0.3048)
			(stroke
				(width 0.1)
				(type default)
			)
			(layer "B.Fab")
		)
		(fp_line
			(start -0.12065 -0.2794)
			(end -0.12065 -0.3048)
			(stroke
				(width 0.1)
				(type default)
			)
			(layer "B.Fab")
		)
		(fp_line
			(start -0.120396 0.2794)
			(end 0.12065 0.2794)
			(stroke
				(width 0.1)
				(type default)
			)
			(layer "B.Fab")
		)
		(fp_line
			(start -0.120396 0.3048)
			(end -0.120396 0.2794)
			(stroke
				(width 0.1)
				(type default)
			)
			(layer "B.Fab")
		)
		(fp_line
			(start 0.12065 -0.305054)
			(end 0.12065 -0.2794)
			(stroke
				(width 0.1)
				(type default)
			)
			(layer "B.Fab")
		)
		(fp_line
			(start 0.12065 -0.2794)
			(end -0.12065 -0.2794)
			(stroke
				(width 0.1)
				(type default)
			)
			(layer "B.Fab")
		)
		(fp_line
			(start 0.12065 0.2794)
			(end 0.12065 0.3048)
			(stroke
				(width 0.1)
				(type default)
			)
			(layer "B.Fab")
		)
		(fp_line
			(start 0.12065 0.3048)
			(end 0.67945 0.3048)
			(stroke
				(width 0.1)
				(type default)
			)
			(layer "B.Fab")
		)
		(fp_line
			(start 0.67945 -0.305054)
			(end 0.12065 -0.305054)
			(stroke
				(width 0.1)
				(type default)
			)
			(layer "B.Fab")
		)
		(fp_line
			(start 0.67945 0.3048)
			(end 0.67945 -0.305054)
			(stroke
				(width 0.1)
				(type default)
			)
			(layer "B.Fab")
		)
		(pad "1" smd circle
			(at 0.40005 0 180)
			(size 0 0)
			(layers "B.Cu" "B.Mask" "B.Paste")
			(net "PVDDCR_CPU0_P0")
		)
		(pad "2" smd circle
			(at -0.40005 0 180)
			(size 0 0)
			(layers "B.Cu" "B.Mask" "B.Paste")
			(net "GND")
		)
	)
	(footprint ""
		(layer "B.Cu")
		(at 321.391026 -398.942052 90)
		(property "Reference" "C567"
			(at 0 0 90)
			(layer "B.SilkS")
			(hide yes)
			(effects
				(font
					(size 1.27 1.27)
				)
				(justify mirror)
			)
		)
		(property "Value" ""
			(at 0 0 90)
			(layer "B.Fab")
			(effects
				(font
					(size 1.27 1.27)
				)
				(justify mirror)
			)
		)
		(duplicate_pad_numbers_are_jumpers no)
		(fp_line
			(start 0.7874 -0.4064)
			(end -0.7874 -0.4064)
			(stroke
				(width 0.1524)
				(type default)
			)
			(layer "B.SilkS")
		)
		(fp_line
			(start -0.7874 -0.4064)
			(end -0.7874 0.4064)
			(stroke
				(width 0.1524)
				(type default)
			)
			(layer "B.SilkS")
		)
		(fp_line
			(start 0.7874 0.4064)
			(end 0.7874 -0.4064)
			(stroke
				(width 0.1524)
				(type default)
			)
			(layer "B.SilkS")
		)
		(fp_line
			(start -0.7874 0.4064)
			(end 0.7874 0.4064)
			(stroke
				(width 0.1524)
				(type default)
			)
			(layer "B.SilkS")
		)
		(fp_line
			(start 0.67945 -0.305054)
			(end 0.12065 -0.305054)
			(stroke
				(width 0.1)
				(type default)
			)
			(layer "B.Fab")
		)
		(fp_line
			(start 0.12065 -0.305054)
			(end 0.12065 -0.2794)
			(stroke
				(width 0.1)
				(type default)
			)
			(layer "B.Fab")
		)
		(fp_line
			(start -0.12065 -0.3048)
			(end -0.67945 -0.3048)
			(stroke
				(width 0.1)
				(type default)
			)
			(layer "B.Fab")
		)
		(fp_line
			(start -0.67945 -0.3048)
			(end -0.67945 0.3048)
			(stroke
				(width 0.1)
				(type default)
			)
			(layer "B.Fab")
		)
		(fp_line
			(start 0.12065 -0.2794)
			(end -0.12065 -0.2794)
			(stroke
				(width 0.1)
				(type default)
			)
			(layer "B.Fab")
		)
		(fp_line
			(start -0.12065 -0.2794)
			(end -0.12065 -0.3048)
			(stroke
				(width 0.1)
				(type default)
			)
			(layer "B.Fab")
		)
		(fp_line
			(start 0.12065 0.2794)
			(end 0.12065 0.3048)
			(stroke
				(width 0.1)
				(type default)
			)
			(layer "B.Fab")
		)
		(fp_line
			(start -0.120396 0.2794)
			(end 0.12065 0.2794)
			(stroke
				(width 0.1)
				(type default)
			)
			(layer "B.Fab")
		)
		(fp_line
			(start 0.67945 0.3048)
			(end 0.67945 -0.305054)
			(stroke
				(width 0.1)
				(type default)
			)
			(layer "B.Fab")
		)
		(fp_line
			(start 0.12065 0.3048)
			(end 0.67945 0.3048)
			(stroke
				(width 0.1)
				(type default)
			)
			(layer "B.Fab")
		)
		(fp_line
			(start -0.120396 0.3048)
			(end -0.120396 0.2794)
			(stroke
				(width 0.1)
				(type default)
			)
			(layer "B.Fab")
		)
		(fp_line
			(start -0.67945 0.3048)
			(end -0.120396 0.3048)
			(stroke
				(width 0.1)
				(type default)
			)
			(layer "B.Fab")
		)
		(pad "1" smd circle
			(at 0.40005 0 270)
			(size 0 0)
			(layers "B.Cu" "B.Mask" "B.Paste")
			(net "P0V9_CPU0_RT0_2A")
		)
		(pad "2" smd circle
			(at -0.40005 0 270)
			(size 0 0)
			(layers "B.Cu" "B.Mask" "B.Paste")
			(net "GND")
		)
	)
	(footprint ""
		(layer "B.Cu")
		(at 348.418912 -258.830064 180)
		(property "Reference" "C2632"
			(at 0 0 0)
			(layer "B.SilkS")
			(hide yes)
			(effects
				(font
					(size 1.27 1.27)
				)
				(justify mirror)
			)
		)
		(property "Value" ""
			(at 0 0 0)
			(layer "B.Fab")
			(effects
				(font
					(size 1.27 1.27)
				)
				(justify mirror)
			)
		)
		(duplicate_pad_numbers_are_jumpers no)
		(fp_line
			(start 0.7874 0.4064)
			(end 0.7874 -0.4064)
			(stroke
				(width 0.1524)
				(type default)
			)
			(layer "B.SilkS")
		)
		(fp_line
			(start 0.7874 -0.4064)
			(end -0.7874 -0.4064)
			(stroke
				(width 0.1524)
				(type default)
			)
			(layer "B.SilkS")
		)
		(fp_line
			(start -0.7874 0.4064)
			(end 0.7874 0.4064)
			(stroke
				(width 0.1524)
				(type default)
			)
			(layer "B.SilkS")
		)
		(fp_line
			(start -0.7874 -0.4064)
			(end -0.7874 0.4064)
			(stroke
				(width 0.1524)
				(type default)
			)
			(layer "B.SilkS")
		)
		(fp_line
			(start 0.67945 0.3048)
			(end 0.67945 -0.305054)
			(stroke
				(width 0.1)
				(type default)
			)
			(layer "B.Fab")
		)
		(fp_line
			(start 0.67945 -0.305054)
			(end 0.12065 -0.305054)
			(stroke
				(width 0.1)
				(type default)
			)
			(layer "B.Fab")
		)
		(fp_line
			(start 0.12065 0.3048)
			(end 0.67945 0.3048)
			(stroke
				(width 0.1)
				(type default)
			)
			(layer "B.Fab")
		)
		(fp_line
			(start 0.12065 0.2794)
			(end 0.12065 0.3048)
			(stroke
				(width 0.1)
				(type default)
			)
			(layer "B.Fab")
		)
		(fp_line
			(start 0.12065 -0.2794)
			(end -0.12065 -0.2794)
			(stroke
				(width 0.1)
				(type default)
			)
			(layer "B.Fab")
		)
		(fp_line
			(start 0.12065 -0.305054)
			(end 0.12065 -0.2794)
			(stroke
				(width 0.1)
				(type default)
			)
			(layer "B.Fab")
		)
		(fp_line
			(start -0.120396 0.3048)
			(end -0.120396 0.2794)
			(stroke
				(width 0.1)
				(type default)
			)
			(layer "B.Fab")
		)
		(fp_line
			(start -0.120396 0.2794)
			(end 0.12065 0.2794)
			(stroke
				(width 0.1)
				(type default)
			)
			(layer "B.Fab")
		)
		(fp_line
			(start -0.12065 -0.2794)
			(end -0.12065 -0.3048)
			(stroke
				(width 0.1)
				(type default)
			)
			(layer "B.Fab")
		)
		(fp_line
			(start -0.12065 -0.3048)
			(end -0.67945 -0.3048)
			(stroke
				(width 0.1)
				(type default)
			)
			(layer "B.Fab")
		)
		(fp_line
			(start -0.67945 0.3048)
			(end -0.120396 0.3048)
			(stroke
				(width 0.1)
				(type default)
			)
			(layer "B.Fab")
		)
		(fp_line
			(start -0.67945 -0.3048)
			(end -0.67945 0.3048)
			(stroke
				(width 0.1)
				(type default)
			)
			(layer "B.Fab")
		)
		(pad "1" smd circle
			(at 0.40005 0)
			(size 0 0)
			(layers "B.Cu" "B.Mask" "B.Paste")
			(net "PVDDIO_P0")
		)
		(pad "2" smd circle
			(at -0.40005 0)
			(size 0 0)
			(layers "B.Cu" "B.Mask" "B.Paste")
			(net "GND")
		)
	)
	(footprint ""
		(layer "B.Cu")
		(at 189.993778 -126.93396 -90)
		(property "Reference" "R6824"
			(at 0 0 90)
			(layer "B.SilkS")
			(hide yes)
			(effects
				(font
					(size 1.27 1.27)
				)
				(justify mirror)
			)
		)
		(property "Value" ""
			(at 0 0 90)
			(layer "B.Fab")
			(effects
				(font
					(size 1.27 1.27)
				)
				(justify mirror)
			)
		)
		(duplicate_pad_numbers_are_jumpers no)
		(fp_line
			(start -0.7874 0.4064)
			(end 0.7874 0.4064)
			(stroke
				(width 0.1524)
				(type default)
			)
			(layer "B.SilkS")
		)
		(fp_line
			(start 0.7874 0.4064)
			(end 0.7874 -0.4064)
			(stroke
				(width 0.1524)
				(type default)
			)
			(layer "B.SilkS")
		)
		(fp_line
			(start -0.7874 -0.4064)
			(end -0.7874 0.4064)
			(stroke
				(width 0.1524)
				(type default)
			)
			(layer "B.SilkS")
		)
		(fp_line
			(start 0.7874 -0.4064)
			(end -0.7874 -0.4064)
			(stroke
				(width 0.1524)
				(type default)
			)
			(layer "B.SilkS")
		)
		(fp_line
			(start -0.67945 0.3048)
			(end -0.120396 0.3048)
			(stroke
				(width 0.1)
				(type default)
			)
			(layer "B.Fab")
		)
		(fp_line
			(start -0.120396 0.3048)
			(end -0.120396 0.2794)
			(stroke
				(width 0.1)
				(type default)
			)
			(layer "B.Fab")
		)
		(fp_line
			(start 0.12065 0.3048)
			(end 0.67945 0.3048)
			(stroke
				(width 0.1)
				(type default)
			)
			(layer "B.Fab")
		)
		(fp_line
			(start 0.67945 0.3048)
			(end 0.67945 -0.305054)
			(stroke
				(width 0.1)
				(type default)
			)
			(layer "B.Fab")
		)
		(fp_line
			(start -0.120396 0.2794)
			(end 0.12065 0.2794)
			(stroke
				(width 0.1)
				(type default)
			)
			(layer "B.Fab")
		)
		(fp_line
			(start 0.12065 0.2794)
			(end 0.12065 0.3048)
			(stroke
				(width 0.1)
				(type default)
			)
			(layer "B.Fab")
		)
		(fp_line
			(start -0.12065 -0.2794)
			(end -0.12065 -0.3048)
			(stroke
				(width 0.1)
				(type default)
			)
			(layer "B.Fab")
		)
		(fp_line
			(start 0.12065 -0.2794)
			(end -0.12065 -0.2794)
			(stroke
				(width 0.1)
				(type default)
			)
			(layer "B.Fab")
		)
		(fp_line
			(start -0.67945 -0.3048)
			(end -0.67945 0.3048)
			(stroke
				(width 0.1)
				(type default)
			)
			(layer "B.Fab")
		)
		(fp_line
			(start -0.12065 -0.3048)
			(end -0.67945 -0.3048)
			(stroke
				(width 0.1)
				(type default)
			)
			(layer "B.Fab")
		)
		(fp_line
			(start 0.12065 -0.305054)
			(end 0.12065 -0.2794)
			(stroke
				(width 0.1)
				(type default)
			)
			(layer "B.Fab")
		)
		(fp_line
			(start 0.67945 -0.305054)
			(end 0.12065 -0.305054)
			(stroke
				(width 0.1)
				(type default)
			)
			(layer "B.Fab")
		)
		(pad "1" smd circle
			(at 0.40005 0 90)
			(size 0 0)
			(layers "B.Cu" "B.Mask" "B.Paste")
			(net "RST_RT_CPU0_P2_RESET_R2_N")
		)
		(pad "2" smd circle
			(at -0.40005 0 90)
			(size 0 0)
			(layers "B.Cu" "B.Mask" "B.Paste")
			(net "RST_RT_CPU0_P2_RESET_R_N")
		)
	)
	(footprint ""
		(layer "B.Cu")
		(at 229.8446 -337.312 180)
		(property "Reference" "R6758"
			(at 0 0 0)
			(layer "B.SilkS")
			(hide yes)
			(effects
				(font
					(size 1.27 1.27)
				)
				(justify mirror)
			)
		)
		(property "Value" ""
			(at 0 0 0)
			(layer "B.Fab")
			(effects
				(font
					(size 1.27 1.27)
				)
				(justify mirror)
			)
		)
		(duplicate_pad_numbers_are_jumpers no)
		(fp_line
			(start 0.32512 0.175006)
			(end 0.32512 -0.175006)
			(stroke
				(width 0.1)
				(type default)
			)
			(layer "B.Fab")
		)
		(fp_line
			(start 0.32512 -0.175006)
			(end -0.32512 -0.175006)
			(stroke
				(width 0.1)
				(type default)
			)
			(layer "B.Fab")
		)
		(fp_line
			(start -0.32512 0.175006)
			(end 0.32512 0.175006)
			(stroke
				(width 0.1)
				(type default)
			)
			(layer "B.Fab")
		)
		(fp_line
			(start -0.32512 -0.175006)
			(end -0.32512 0.175006)
			(stroke
				(width 0.1)
				(type default)
			)
			(layer "B.Fab")
		)
		(pad "1" smd rect
			(at 0.2667 0)
			(size 0.3048 0.381)
			(layers "B.Cu" "B.Mask" "B.Paste")
			(net "SMB_RT_CPU0_P3_SDA")
		)
		(pad "2" smd rect
			(at -0.2667 0 180)
			(size 0.3048 0.381)
			(layers "B.Cu" "B.Mask" "B.Paste")
			(net "SMB_RT_CPU0_P3_R_SDA")
		)
	)
	(footprint ""
		(layer "B.Cu")
		(at 356.565962 -256.012188 -90)
		(property "Reference" "C2547"
			(at 0 0 90)
			(layer "B.SilkS")
			(hide yes)
			(effects
				(font
					(size 1.27 1.27)
				)
				(justify mirror)
			)
		)
		(property "Value" ""
			(at 0 0 90)
			(layer "B.Fab")
			(effects
				(font
					(size 1.27 1.27)
				)
				(justify mirror)
			)
		)
		(duplicate_pad_numbers_are_jumpers no)
		(fp_line
			(start -0.7874 0.4064)
			(end 0.7874 0.4064)
			(stroke
				(width 0.1524)
				(type default)
			)
			(layer "B.SilkS")
		)
		(fp_line
			(start 0.7874 0.4064)
			(end 0.7874 -0.4064)
			(stroke
				(width 0.1524)
				(type default)
			)
			(layer "B.SilkS")
		)
		(fp_line
			(start -0.7874 -0.4064)
			(end -0.7874 0.4064)
			(stroke
				(width 0.1524)
				(type default)
			)
			(layer "B.SilkS")
		)
		(fp_line
			(start 0.7874 -0.4064)
			(end -0.7874 -0.4064)
			(stroke
				(width 0.1524)
				(type default)
			)
			(layer "B.SilkS")
		)
		(fp_line
			(start -0.67945 0.3048)
			(end -0.120396 0.3048)
			(stroke
				(width 0.1)
				(type default)
			)
			(layer "B.Fab")
		)
		(fp_line
			(start -0.120396 0.3048)
			(end -0.120396 0.2794)
			(stroke
				(width 0.1)
				(type default)
			)
			(layer "B.Fab")
		)
		(fp_line
			(start 0.12065 0.3048)
			(end 0.67945 0.3048)
			(stroke
				(width 0.1)
				(type default)
			)
			(layer "B.Fab")
		)
		(fp_line
			(start 0.67945 0.3048)
			(end 0.67945 -0.305054)
			(stroke
				(width 0.1)
				(type default)
			)
			(layer "B.Fab")
		)
		(fp_line
			(start -0.120396 0.2794)
			(end 0.12065 0.2794)
			(stroke
				(width 0.1)
				(type default)
			)
			(layer "B.Fab")
		)
		(fp_line
			(start 0.12065 0.2794)
			(end 0.12065 0.3048)
			(stroke
				(width 0.1)
				(type default)
			)
			(layer "B.Fab")
		)
		(fp_line
			(start -0.12065 -0.2794)
			(end -0.12065 -0.3048)
			(stroke
				(width 0.1)
				(type default)
			)
			(layer "B.Fab")
		)
		(fp_line
			(start 0.12065 -0.2794)
			(end -0.12065 -0.2794)
			(stroke
				(width 0.1)
				(type default)
			)
			(layer "B.Fab")
		)
		(fp_line
			(start -0.67945 -0.3048)
			(end -0.67945 0.3048)
			(stroke
				(width 0.1)
				(type default)
			)
			(layer "B.Fab")
		)
		(fp_line
			(start -0.12065 -0.3048)
			(end -0.67945 -0.3048)
			(stroke
				(width 0.1)
				(type default)
			)
			(layer "B.Fab")
		)
		(fp_line
			(start 0.12065 -0.305054)
			(end 0.12065 -0.2794)
			(stroke
				(width 0.1)
				(type default)
			)
			(layer "B.Fab")
		)
		(fp_line
			(start 0.67945 -0.305054)
			(end 0.12065 -0.305054)
			(stroke
				(width 0.1)
				(type default)
			)
			(layer "B.Fab")
		)
		(pad "1" smd circle
			(at 0.40005 0 90)
			(size 0 0)
			(layers "B.Cu" "B.Mask" "B.Paste")
			(net "PVDDCR_SOC_P0")
		)
		(pad "2" smd circle
			(at -0.40005 0 90)
			(size 0 0)
			(layers "B.Cu" "B.Mask" "B.Paste")
			(net "GND")
		)
	)
	(footprint ""
		(layer "B.Cu")
		(at 68.318634 -203.501752 -90)
		(property "Reference" "R512"
			(at 0 0 90)
			(layer "B.SilkS")
			(hide yes)
			(effects
				(font
					(size 1.27 1.27)
				)
				(justify mirror)
			)
		)
		(property "Value" ""
			(at 0 0 90)
			(layer "B.Fab")
			(effects
				(font
					(size 1.27 1.27)
				)
				(justify mirror)
			)
		)
		(duplicate_pad_numbers_are_jumpers no)
		(fp_line
			(start -0.7874 0.4064)
			(end 0.7874 0.4064)
			(stroke
				(width 0.1524)
				(type default)
			)
			(layer "B.SilkS")
		)
		(fp_line
			(start 0.7874 0.4064)
			(end 0.7874 -0.4064)
			(stroke
				(width 0.1524)
				(type default)
			)
			(layer "B.SilkS")
		)
		(fp_line
			(start -0.7874 -0.4064)
			(end -0.7874 0.4064)
			(stroke
				(width 0.1524)
				(type default)
			)
			(layer "B.SilkS")
		)
		(fp_line
			(start 0.7874 -0.4064)
			(end -0.7874 -0.4064)
			(stroke
				(width 0.1524)
				(type default)
			)
			(layer "B.SilkS")
		)
		(fp_line
			(start -0.67945 0.3048)
			(end -0.120396 0.3048)
			(stroke
				(width 0.1)
				(type default)
			)
			(layer "B.Fab")
		)
		(fp_line
			(start -0.120396 0.3048)
			(end -0.120396 0.2794)
			(stroke
				(width 0.1)
				(type default)
			)
			(layer "B.Fab")
		)
		(fp_line
			(start 0.12065 0.3048)
			(end 0.67945 0.3048)
			(stroke
				(width 0.1)
				(type default)
			)
			(layer "B.Fab")
		)
		(fp_line
			(start 0.67945 0.3048)
			(end 0.67945 -0.305054)
			(stroke
				(width 0.1)
				(type default)
			)
			(layer "B.Fab")
		)
		(fp_line
			(start -0.120396 0.2794)
			(end 0.12065 0.2794)
			(stroke
				(width 0.1)
				(type default)
			)
			(layer "B.Fab")
		)
		(fp_line
			(start 0.12065 0.2794)
			(end 0.12065 0.3048)
			(stroke
				(width 0.1)
				(type default)
			)
			(layer "B.Fab")
		)
		(fp_line
			(start -0.12065 -0.2794)
			(end -0.12065 -0.3048)
			(stroke
				(width 0.1)
				(type default)
			)
			(layer "B.Fab")
		)
		(fp_line
			(start 0.12065 -0.2794)
			(end -0.12065 -0.2794)
			(stroke
				(width 0.1)
				(type default)
			)
			(layer "B.Fab")
		)
		(fp_line
			(start -0.67945 -0.3048)
			(end -0.67945 0.3048)
			(stroke
				(width 0.1)
				(type default)
			)
			(layer "B.Fab")
		)
		(fp_line
			(start -0.12065 -0.3048)
			(end -0.67945 -0.3048)
			(stroke
				(width 0.1)
				(type default)
			)
			(layer "B.Fab")
		)
		(fp_line
			(start 0.12065 -0.305054)
			(end 0.12065 -0.2794)
			(stroke
				(width 0.1)
				(type default)
			)
			(layer "B.Fab")
		)
		(fp_line
			(start 0.67945 -0.305054)
			(end 0.12065 -0.305054)
			(stroke
				(width 0.1)
				(type default)
			)
			(layer "B.Fab")
		)
		(pad "1" smd circle
			(at 0.40005 0 90)
			(size 0 0)
			(layers "B.Cu" "B.Mask" "B.Paste")
			(net "P3V3_AUX")
		)
		(pad "2" smd circle
			(at -0.40005 0 90)
			(size 0 0)
			(layers "B.Cu" "B.Mask" "B.Paste")
			(net "CPU1_CORETYPE2")
		)
	)
)
